(kicad_pcb
	(version 20260206)
	(generator "pcbnew")
	(generator_version "10.0")
	(general
		(thickness 1.6)
		(legacy_teardrops no)
	)
	(paper "A4")
	(title_block
		(title "Wiwynn_Tioga_Pass_MB.brd")
		(comment 1 "Tioga Pass / footprint 190 of 4770 (U2D1), pads 912-1015 of 3647")
	)
	(layers
		(0 "F.Cu" signal "TOP")
		(4 "In1.Cu" signal "L2GND")
		(6 "In2.Cu" signal "L3")
		(8 "In3.Cu" signal "L4GND")
		(10 "In4.Cu" signal "L5")
		(12 "In5.Cu" signal "L6GND")
		(14 "In6.Cu" signal "L7VCC")
		(16 "In7.Cu" signal "L8VCC")
		(18 "In8.Cu" signal "L9GND")
		(20 "In9.Cu" signal "L10")
		(22 "In10.Cu" signal "L11GND")
		(24 "In11.Cu" signal "L12")
		(26 "In12.Cu" signal "L13GND")
		(2 "B.Cu" signal "BOTTOM")
		(9 "F.Adhes" user "F.Adhesive")
		(11 "B.Adhes" user "B.Adhesive")
		(13 "F.Paste" user "Package Geometry/Pastemask Top")
		(15 "B.Paste" user "Package Geometry/Pastemask Bottom")
		(5 "F.SilkS" user "Ref Des/Silkscreen Top")
		(7 "B.SilkS" user "Ref Des/Silkscreen Bottom")
		(1 "F.Mask" user "Board Geometry/Soldermask Top")
		(3 "B.Mask" user "Board Geometry/Soldermask Bottom")
		(17 "Dwgs.User" user "User.Drawings")
		(19 "Cmts.User" user "User.Comments")
		(21 "Eco1.User" user "User.Eco1")
		(23 "Eco2.User" user "User.Eco2")
		(25 "Edge.Cuts" user "Board Geometry/Outline")
		(27 "Margin" user)
		(31 "F.CrtYd" user "Package Geometry/Place Bound Top")
		(29 "B.CrtYd" user "Package Geometry/Place Bound Bottom")
		(35 "F.Fab" user "Ref Des/Assembly Top")
		(33 "B.Fab" user "Ref Des/Assembly Bottom")
	)
	(footprint ""
		(layer "F.Cu")
		(at 104.99979 -76.550012 180)
		(property "Reference" "U2D1"
			(at 25.19299 30.484318 0)
			(unlocked yes)
			(layer "F.SilkS")
			(effects
				(font
					(size 0.7874 0.5842)
					(thickness 0.1524)
				)
			)
		)
		(property "Value" ""
			(at 0 0 180)
			(layer "F.Fab")
			(effects
				(font
					(size 1.27 1.27)
				)
			)
		)
		(duplicate_pad_numbers_are_jumpers no)
		(pad "BF83" smd circle
			(at 34.675064 -4.614926)
			(size 0.4318 0.4318)
			(layers "F.Cu" "F.Mask" "F.Paste")
			(net "PVCCIN_CPU1")
		)
		(pad "BF85" smd custom
			(at 36.392104 -4.614926 270)
			(size 0.10795 0.10795)
			(layers "F.Cu" "F.Mask" "F.Paste")
			(net "PVCCIN_CPU1")
			(options
				(clearance outline)
				(anchor circle)
			)
			(primitives
				(gr_poly
					(pts
						(arc
							(start 0.2159 -0.0381)
							(mid 0 -0.254)
							(end -0.2159 -0.0381)
						)
						(arc
							(start -0.2159 0.0381)
							(mid 0 0.254)
							(end 0.2159 0.0381)
						)
					)
					(width 0)
					(fill yes)
				)
			)
		)
		(pad "BG4" smd circle
			(at -34.675064 -2.319274)
			(size 0.4318 0.4318)
			(layers "F.Cu" "F.Mask" "F.Paste")
			(net "UPI_CPU1_CPU0_P0P0_DP<19>")
		)
		(pad "BG6" smd circle
			(at -32.958024 -2.319274)
			(size 0.4318 0.4318)
			(layers "F.Cu" "F.Mask" "F.Paste")
			(net "GND")
		)
		(pad "BG8" smd circle
			(at -31.240984 -2.319274)
			(size 0.4318 0.4318)
			(layers "F.Cu" "F.Mask" "F.Paste")
			(net "GND")
		)
		(pad "BG10" smd circle
			(at -29.523944 -2.319274)
			(size 0.4318 0.4318)
			(layers "F.Cu" "F.Mask" "F.Paste")
			(net "GND")
		)
		(pad "BG12" smd circle
			(at -27.806904 -2.319274)
			(size 0.4318 0.4318)
			(layers "F.Cu" "F.Mask" "F.Paste")
			(net "PVCCMCP_CPU1")
		)
		(pad "BG14" smd circle
			(at -26.090118 -2.319274)
			(size 0.4318 0.4318)
			(layers "F.Cu" "F.Mask" "F.Paste")
			(net "PVCCMCP_CPU1")
		)
		(pad "BG16" smd circle
			(at -24.373078 -2.319274)
			(size 0.4318 0.4318)
			(layers "F.Cu" "F.Mask" "F.Paste")
			(net "CLK_156M_OSC_CPU1_HFI_DP")
		)
		(pad "BG18" smd circle
			(at -22.656038 -2.319274)
			(size 0.4318 0.4318)
			(layers "F.Cu" "F.Mask" "F.Paste")
			(net "TP_CPU1_RSVD_145")
		)
		(pad "BG20" smd circle
			(at -20.938998 -2.319274)
			(size 0.4318 0.4318)
			(layers "F.Cu" "F.Mask" "F.Paste")
			(net "TP_CPU1_RSVD_144")
		)
		(pad "BG22" smd circle
			(at -19.221958 -2.319274)
			(size 0.4318 0.4318)
			(layers "F.Cu" "F.Mask" "F.Paste")
			(net "GND")
		)
		(pad "BG24" smd circle
			(at -17.504918 -2.319274)
			(size 0.4318 0.4318)
			(layers "F.Cu" "F.Mask" "F.Paste")
			(net "GND")
		)
		(pad "BG26" smd circle
			(at -15.787878 -2.319274)
			(size 0.4318 0.4318)
			(layers "F.Cu" "F.Mask" "F.Paste")
			(net "PVCCIO_CPU1")
		)
		(pad "BG60" smd circle
			(at 14.929612 -4.119372)
			(size 0.508 0.508)
			(layers "F.Cu" "F.Mask" "F.Paste")
			(net "PVCCIN_CPU1")
		)
		(pad "BG62" smd circle
			(at 16.646398 -4.119372)
			(size 0.4318 0.4318)
			(layers "F.Cu" "F.Mask" "F.Paste")
			(net "PVCCIN_CPU1")
		)
		(pad "BG64" smd circle
			(at 18.363438 -4.119372)
			(size 0.4318 0.4318)
			(layers "F.Cu" "F.Mask" "F.Paste")
			(net "PVCCIN_CPU1")
		)
		(pad "BG66" smd circle
			(at 20.080478 -4.119372)
			(size 0.4318 0.4318)
			(layers "F.Cu" "F.Mask" "F.Paste")
			(net "PVCCIN_CPU1")
		)
		(pad "BG68" smd circle
			(at 21.797518 -4.119372)
			(size 0.4318 0.4318)
			(layers "F.Cu" "F.Mask" "F.Paste")
			(net "PVCCIN_CPU1")
		)
		(pad "BG70" smd circle
			(at 23.514558 -4.119372)
			(size 0.4318 0.4318)
			(layers "F.Cu" "F.Mask" "F.Paste")
			(net "PVCCIN_CPU1")
		)
		(pad "BG72" smd circle
			(at 25.231598 -4.119372)
			(size 0.4318 0.4318)
			(layers "F.Cu" "F.Mask" "F.Paste")
			(net "GND")
		)
		(pad "BG74" smd circle
			(at 26.948384 -4.119372)
			(size 0.4318 0.4318)
			(layers "F.Cu" "F.Mask" "F.Paste")
			(net "GND")
		)
		(pad "BG76" smd circle
			(at 28.665424 -4.119372)
			(size 0.4318 0.4318)
			(layers "F.Cu" "F.Mask" "F.Paste")
			(net "GND")
		)
		(pad "BG78" smd circle
			(at 30.382464 -4.119372)
			(size 0.4318 0.4318)
			(layers "F.Cu" "F.Mask" "F.Paste")
			(net "GND")
		)
		(pad "BG80" smd circle
			(at 32.099504 -4.119372)
			(size 0.4318 0.4318)
			(layers "F.Cu" "F.Mask" "F.Paste")
			(net "GND")
		)
		(pad "BG82" smd circle
			(at 33.816544 -4.119372)
			(size 0.4318 0.4318)
			(layers "F.Cu" "F.Mask" "F.Paste")
			(net "GND")
		)
		(pad "BG84" smd custom
			(at 35.533584 -4.119372 270)
			(size 0.10795 0.10795)
			(layers "F.Cu" "F.Mask" "F.Paste")
			(net "PVCCIN_CPU1")
			(options
				(clearance outline)
				(anchor circle)
			)
			(primitives
				(gr_poly
					(pts
						(arc
							(start 0.2159 -0.0381)
							(mid 0 -0.254)
							(end -0.2159 -0.0381)
						)
						(arc
							(start -0.2159 0.0381)
							(mid 0 0.254)
							(end 0.2159 0.0381)
						)
					)
					(width 0)
					(fill yes)
				)
			)
		)
		(pad "BH3" smd custom
			(at -35.533584 -1.824228 90)
			(size 0.10795 0.10795)
			(layers "F.Cu" "F.Mask" "F.Paste")
			(net "UPI_CPU1_CPU0_P0P0_DN<19>")
			(options
				(clearance outline)
				(anchor circle)
			)
			(primitives
				(gr_poly
					(pts
						(arc
							(start 0.2159 -0.0381)
							(mid 0 -0.254)
							(end -0.2159 -0.0381)
						)
						(arc
							(start -0.2159 0.0381)
							(mid 0 0.254)
							(end 0.2159 0.0381)
						)
					)
					(width 0)
					(fill yes)
				)
			)
		)
		(pad "BH5" smd circle
			(at -33.816544 -1.824228)
			(size 0.4318 0.4318)
			(layers "F.Cu" "F.Mask" "F.Paste")
			(net "VSENSE_PVCCIO_CPU1_SKT_VSEN")
		)
		(pad "BH7" smd circle
			(at -32.099504 -1.824228)
			(size 0.4318 0.4318)
			(layers "F.Cu" "F.Mask" "F.Paste")
			(net "GND")
		)
		(pad "BH9" smd circle
			(at -30.382464 -1.824228)
			(size 0.4318 0.4318)
			(layers "F.Cu" "F.Mask" "F.Paste")
			(net "GND")
		)
		(pad "BH11" smd circle
			(at -28.665424 -1.824228)
			(size 0.4318 0.4318)
			(layers "F.Cu" "F.Mask" "F.Paste")
			(net "GND")
		)
		(pad "BH13" smd circle
			(at -26.948384 -1.824228)
			(size 0.4318 0.4318)
			(layers "F.Cu" "F.Mask" "F.Paste")
			(net "PVCCMCP_CPU1")
		)
		(pad "BH15" smd circle
			(at -25.231598 -1.824228)
			(size 0.4318 0.4318)
			(layers "F.Cu" "F.Mask" "F.Paste")
			(net "GND")
		)
		(pad "BH17" smd circle
			(at -23.514558 -1.824228)
			(size 0.4318 0.4318)
			(layers "F.Cu" "F.Mask" "F.Paste")
			(net "GND")
		)
		(pad "BH19" smd circle
			(at -21.797518 -1.824228)
			(size 0.4318 0.4318)
			(layers "F.Cu" "F.Mask" "F.Paste")
			(net "PVCCMCP_CPU1")
		)
		(pad "BH21" smd circle
			(at -20.080478 -1.824228)
			(size 0.4318 0.4318)
			(layers "F.Cu" "F.Mask" "F.Paste")
			(net "GND")
		)
		(pad "BH23" smd circle
			(at -18.363438 -1.824228)
			(size 0.4318 0.4318)
			(layers "F.Cu" "F.Mask" "F.Paste")
			(net "TP_CD_HFI1_CPU1_I2CDAT")
		)
		(pad "BH25" smd circle
			(at -16.646398 -1.824228)
			(size 0.4318 0.4318)
			(layers "F.Cu" "F.Mask" "F.Paste")
			(net "PVCCIO_CPU1")
		)
		(pad "BH27" smd circle
			(at -14.929612 -1.824228)
			(size 0.4318 0.4318)
			(layers "F.Cu" "F.Mask" "F.Paste")
			(net "PVCCIO_CPU1")
		)
		(pad "BH61" smd circle
			(at 15.787878 -3.624326)
			(size 0.4318 0.4318)
			(layers "F.Cu" "F.Mask" "F.Paste")
			(net "PVCCIN_CPU1")
		)
		(pad "BH63" smd circle
			(at 17.504918 -3.624326)
			(size 0.4318 0.4318)
			(layers "F.Cu" "F.Mask" "F.Paste")
			(net "PVCCIN_CPU1")
		)
		(pad "BH65" smd circle
			(at 19.221958 -3.624326)
			(size 0.4318 0.4318)
			(layers "F.Cu" "F.Mask" "F.Paste")
			(net "PVCCIN_CPU1")
		)
		(pad "BH67" smd circle
			(at 20.938998 -3.624326)
			(size 0.4318 0.4318)
			(layers "F.Cu" "F.Mask" "F.Paste")
			(net "PVCCIN_CPU1")
		)
		(pad "BH69" smd circle
			(at 22.656038 -3.624326)
			(size 0.4318 0.4318)
			(layers "F.Cu" "F.Mask" "F.Paste")
			(net "PVCCIN_CPU1")
		)
		(pad "BH71" smd circle
			(at 24.373078 -3.624326)
			(size 0.4318 0.4318)
			(layers "F.Cu" "F.Mask" "F.Paste")
			(net "PVCCIN_CPU1")
		)
		(pad "BH73" smd circle
			(at 26.090118 -3.624326)
			(size 0.4318 0.4318)
			(layers "F.Cu" "F.Mask" "F.Paste")
			(net "PVCCIN_CPU1")
		)
		(pad "BH75" smd circle
			(at 27.806904 -3.624326)
			(size 0.4318 0.4318)
			(layers "F.Cu" "F.Mask" "F.Paste")
			(net "PVCCIN_CPU1")
		)
		(pad "BH77" smd circle
			(at 29.523944 -3.624326)
			(size 0.4318 0.4318)
			(layers "F.Cu" "F.Mask" "F.Paste")
			(net "PVCCIN_CPU1")
		)
		(pad "BH79" smd circle
			(at 31.240984 -3.624326)
			(size 0.4318 0.4318)
			(layers "F.Cu" "F.Mask" "F.Paste")
			(net "PVCCIN_CPU1")
		)
		(pad "BH81" smd circle
			(at 32.958024 -3.624326)
			(size 0.4318 0.4318)
			(layers "F.Cu" "F.Mask" "F.Paste")
			(net "PVCCIN_CPU1")
		)
		(pad "BH83" smd circle
			(at 34.675064 -3.624326)
			(size 0.4318 0.4318)
			(layers "F.Cu" "F.Mask" "F.Paste")
			(net "PVCCIN_CPU1")
		)
		(pad "BJ4" smd circle
			(at -34.675064 -1.328674)
			(size 0.4318 0.4318)
			(layers "F.Cu" "F.Mask" "F.Paste")
			(net "GND")
		)
		(pad "BJ6" smd circle
			(at -32.958024 -1.328674)
			(size 0.4318 0.4318)
			(layers "F.Cu" "F.Mask" "F.Paste")
			(net "GND")
		)
		(pad "BJ8" smd circle
			(at -31.240984 -1.328674)
			(size 0.4318 0.4318)
			(layers "F.Cu" "F.Mask" "F.Paste")
			(net "TP_P3E_CPU1_PE2_RSR_RXP<14>")
		)
		(pad "BJ10" smd circle
			(at -29.523944 -1.328674)
			(size 0.4318 0.4318)
			(layers "F.Cu" "F.Mask" "F.Paste")
			(net "TP_P3E_CPU1_PE2_RSR_RXP<15>")
		)
		(pad "BJ12" smd circle
			(at -27.806904 -1.328674)
			(size 0.4318 0.4318)
			(layers "F.Cu" "F.Mask" "F.Paste")
			(net "PVCCMCP_CPU1")
		)
		(pad "BJ14" smd circle
			(at -26.090118 -1.328674)
			(size 0.4318 0.4318)
			(layers "F.Cu" "F.Mask" "F.Paste")
			(net "PVCCMCP_CPU1")
		)
		(pad "BJ16" smd circle
			(at -24.373078 -1.328674)
			(size 0.4318 0.4318)
			(layers "F.Cu" "F.Mask" "F.Paste")
			(net "PVCCMCP_CPU1")
		)
		(pad "BJ18" smd circle
			(at -22.656038 -1.328674)
			(size 0.4318 0.4318)
			(layers "F.Cu" "F.Mask" "F.Paste")
			(net "PVCCMCP_CPU1")
		)
		(pad "BJ20" smd circle
			(at -20.938998 -1.328674)
			(size 0.4318 0.4318)
			(layers "F.Cu" "F.Mask" "F.Paste")
			(net "PVCCMCP_CPU1")
		)
		(pad "BJ22" smd circle
			(at -19.221958 -1.328674)
			(size 0.4318 0.4318)
			(layers "F.Cu" "F.Mask" "F.Paste")
			(net "TP_CD_HFI1_CPU1_I2CLK")
		)
		(pad "BJ24" smd circle
			(at -17.504918 -1.328674)
			(size 0.4318 0.4318)
			(layers "F.Cu" "F.Mask" "F.Paste")
			(net "PVCCIO_CPU1")
		)
		(pad "BJ26" smd circle
			(at -15.787878 -1.328674)
			(size 0.4318 0.4318)
			(layers "F.Cu" "F.Mask" "F.Paste")
			(net "PVCCIO_CPU1")
		)
		(pad "BJ60" smd circle
			(at 14.929612 -3.128772)
			(size 0.508 0.508)
			(layers "F.Cu" "F.Mask" "F.Paste")
			(net "PVCCIN_CPU1")
		)
		(pad "BJ62" smd circle
			(at 16.646398 -3.128772)
			(size 0.4318 0.4318)
			(layers "F.Cu" "F.Mask" "F.Paste")
			(net "PVCCIN_CPU1")
		)
		(pad "BJ64" smd circle
			(at 18.363438 -3.128772)
			(size 0.4318 0.4318)
			(layers "F.Cu" "F.Mask" "F.Paste")
			(net "PVCCIN_CPU1")
		)
		(pad "BJ66" smd circle
			(at 20.080478 -3.128772)
			(size 0.4318 0.4318)
			(layers "F.Cu" "F.Mask" "F.Paste")
			(net "PVCCIN_CPU1")
		)
		(pad "BJ68" smd circle
			(at 21.797518 -3.128772)
			(size 0.4318 0.4318)
			(layers "F.Cu" "F.Mask" "F.Paste")
			(net "PVCCIN_CPU1")
		)
		(pad "BJ70" smd circle
			(at 23.514558 -3.128772)
			(size 0.4318 0.4318)
			(layers "F.Cu" "F.Mask" "F.Paste")
			(net "PVCCIN_CPU1")
		)
		(pad "BJ72" smd circle
			(at 25.231598 -3.128772)
			(size 0.4318 0.4318)
			(layers "F.Cu" "F.Mask" "F.Paste")
			(net "PVCCIN_CPU1")
		)
		(pad "BJ74" smd circle
			(at 26.948384 -3.128772)
			(size 0.4318 0.4318)
			(layers "F.Cu" "F.Mask" "F.Paste")
			(net "PVCCIN_CPU1")
		)
		(pad "BJ76" smd circle
			(at 28.665424 -3.128772)
			(size 0.4318 0.4318)
			(layers "F.Cu" "F.Mask" "F.Paste")
			(net "PVCCIN_CPU1")
		)
		(pad "BJ78" smd circle
			(at 30.382464 -3.128772)
			(size 0.4318 0.4318)
			(layers "F.Cu" "F.Mask" "F.Paste")
			(net "PVCCIN_CPU1")
		)
		(pad "BJ80" smd circle
			(at 32.099504 -3.128772)
			(size 0.4318 0.4318)
			(layers "F.Cu" "F.Mask" "F.Paste")
			(net "PVCCIN_CPU1")
		)
		(pad "BJ82" smd circle
			(at 33.816544 -3.128772)
			(size 0.4318 0.4318)
			(layers "F.Cu" "F.Mask" "F.Paste")
			(net "PVCCIN_CPU1")
		)
		(pad "BJ84" smd custom
			(at 35.533584 -3.128772 270)
			(size 0.10795 0.10795)
			(layers "F.Cu" "F.Mask" "F.Paste")
			(net "PVCCIN_CPU1")
			(options
				(clearance outline)
				(anchor circle)
			)
			(primitives
				(gr_poly
					(pts
						(arc
							(start 0.2159 -0.0381)
							(mid 0 -0.254)
							(end -0.2159 -0.0381)
						)
						(arc
							(start -0.2159 0.0381)
							(mid 0 0.254)
							(end 0.2159 0.0381)
						)
					)
					(width 0)
					(fill yes)
				)
			)
		)
		(pad "BK3" smd custom
			(at -35.533584 -0.833628 90)
			(size 0.10795 0.10795)
			(layers "F.Cu" "F.Mask" "F.Paste")
			(net "GND")
			(options
				(clearance outline)
				(anchor circle)
			)
			(primitives
				(gr_poly
					(pts
						(arc
							(start 0.2159 -0.0381)
							(mid 0 -0.254)
							(end -0.2159 -0.0381)
						)
						(arc
							(start -0.2159 0.0381)
							(mid 0 0.254)
							(end 0.2159 0.0381)
						)
					)
					(width 0)
					(fill yes)
				)
			)
		)
		(pad "BK5" smd circle
			(at -33.816544 -0.833628)
			(size 0.4318 0.4318)
			(layers "F.Cu" "F.Mask" "F.Paste")
			(net "TP_P3E_CPU1_PE2_RSR_TXP<15>")
		)
		(pad "BK7" smd circle
			(at -32.099504 -0.833628)
			(size 0.4318 0.4318)
			(layers "F.Cu" "F.Mask" "F.Paste")
			(net "GND")
		)
		(pad "BK9" smd circle
			(at -30.382464 -0.833628)
			(size 0.4318 0.4318)
			(layers "F.Cu" "F.Mask" "F.Paste")
			(net "TP_P3E_CPU1_PE2_RSR_RXN<15>")
		)
		(pad "BK11" smd circle
			(at -28.665424 -0.833628)
			(size 0.4318 0.4318)
			(layers "F.Cu" "F.Mask" "F.Paste")
			(net "GND")
		)
		(pad "BK13" smd circle
			(at -26.948384 -0.833628)
			(size 0.4318 0.4318)
			(layers "F.Cu" "F.Mask" "F.Paste")
			(net "PVCCMCP_CPU1")
		)
		(pad "BK15" smd circle
			(at -25.231598 -0.833628)
			(size 0.4318 0.4318)
			(layers "F.Cu" "F.Mask" "F.Paste")
			(net "PVCCMCP_CPU1")
		)
		(pad "BK17" smd circle
			(at -23.514558 -0.833628)
			(size 0.4318 0.4318)
			(layers "F.Cu" "F.Mask" "F.Paste")
			(net "PVCCMCP_CPU1")
		)
		(pad "BK19" smd circle
			(at -21.797518 -0.833628)
			(size 0.4318 0.4318)
			(layers "F.Cu" "F.Mask" "F.Paste")
			(net "GND")
		)
		(pad "BK21" smd circle
			(at -20.080478 -0.833628)
			(size 0.4318 0.4318)
			(layers "F.Cu" "F.Mask" "F.Paste")
			(net "TP_LED_CPU1_CD_HFI0_N")
		)
		(pad "BK23" smd circle
			(at -18.363438 -0.833628)
			(size 0.4318 0.4318)
			(layers "F.Cu" "F.Mask" "F.Paste")
			(net "TP_CD_HFI1_CPU1_RESET_N")
		)
		(pad "BK25" smd circle
			(at -16.646398 -0.833628)
			(size 0.4318 0.4318)
			(layers "F.Cu" "F.Mask" "F.Paste")
			(net "PVCCIO_CPU1")
		)
		(pad "BK27" smd circle
			(at -14.929612 -0.833628)
			(size 0.4318 0.4318)
			(layers "F.Cu" "F.Mask" "F.Paste")
			(net "PVCCIO_CPU1")
		)
		(pad "BK61" smd circle
			(at 15.787878 -2.633726)
			(size 0.4318 0.4318)
			(layers "F.Cu" "F.Mask" "F.Paste")
			(net "PVCCIN_CPU1")
		)
		(pad "BK63" smd circle
			(at 17.504918 -2.633726)
			(size 0.4318 0.4318)
			(layers "F.Cu" "F.Mask" "F.Paste")
			(net "PVCCIN_CPU1")
		)
		(pad "BK65" smd circle
			(at 19.221958 -2.633726)
			(size 0.4318 0.4318)
			(layers "F.Cu" "F.Mask" "F.Paste")
			(net "PVCCIN_CPU1")
		)
		(pad "BK67" smd circle
			(at 20.938998 -2.633726)
			(size 0.4318 0.4318)
			(layers "F.Cu" "F.Mask" "F.Paste")
			(net "PVCCIN_CPU1")
		)
		(pad "BK69" smd circle
			(at 22.656038 -2.633726)
			(size 0.4318 0.4318)
			(layers "F.Cu" "F.Mask" "F.Paste")
			(net "PVCCIN_CPU1")
		)
		(pad "BK71" smd circle
			(at 24.373078 -2.633726)
			(size 0.4318 0.4318)
			(layers "F.Cu" "F.Mask" "F.Paste")
			(net "PVCCIN_CPU1")
		)
		(pad "BK73" smd circle
			(at 26.090118 -2.633726)
			(size 0.4318 0.4318)
			(layers "F.Cu" "F.Mask" "F.Paste")
			(net "PVCCIN_CPU1")
		)
		(pad "BK75" smd circle
			(at 27.806904 -2.633726)
			(size 0.4318 0.4318)
			(layers "F.Cu" "F.Mask" "F.Paste")
			(net "PVCCIN_CPU1")
		)
		(pad "BK77" smd circle
			(at 29.523944 -2.633726)
			(size 0.4318 0.4318)
			(layers "F.Cu" "F.Mask" "F.Paste")
			(net "PVCCIN_CPU1")
		)
		(pad "BK79" smd circle
			(at 31.240984 -2.633726)
			(size 0.4318 0.4318)
			(layers "F.Cu" "F.Mask" "F.Paste")
			(net "PVCCIN_CPU1")
		)
		(pad "BK81" smd circle
			(at 32.958024 -2.633726)
			(size 0.4318 0.4318)
			(layers "F.Cu" "F.Mask" "F.Paste")
			(net "PVCCIN_CPU1")
		)
		(pad "BK83" smd circle
			(at 34.675064 -2.633726)
			(size 0.4318 0.4318)
			(layers "F.Cu" "F.Mask" "F.Paste")
			(net "PVCCIN_CPU1")
		)
		(pad "BL4" smd circle
			(at -34.675064 -0.338074)
			(size 0.4318 0.4318)
			(layers "F.Cu" "F.Mask" "F.Paste")
			(net "TP_P3E_CPU1_PE2_RSR_TXN<14>")
		)
		(pad "BL6" smd circle
			(at -32.958024 -0.338074)
			(size 0.4318 0.4318)
			(layers "F.Cu" "F.Mask" "F.Paste")
			(net "GND")
		)
	)
)
